FILE_TYPE = CONNECTIVITY;
{Allegro Design Entry HDL 16.6-p007 (v16-6-112F) 10/10/2012}
"PAGE_NUMBER" = 5;
0"NC";
END.
